FILE_TYPE = CONNECTIVITY;
{Allegro Design Entry HDL 16.6-p007 (v16-6-112F) 10/10/2012}
"PAGE_NUMBER" = 90;
0"NC";
1"GND\g";
2"PVCCIO_CPU0\g";
3"GND\g";
4"PVCCIO_CPU0\g";
5"PVCCIO_CPU1\g";
6"PVCCIO_CPU1\g";
7"GND\g";
8"GND\g";
9"GND\g";
10"GND\g";
11"PD_CPU0_DMIMODE_OVERRIDE";
12"PD_CPU1_TXT_PLTEN";
13"PU_CPU1_SOCKET_ID_0";
14"PU_CPU1_SOCKET_ID_1";
15"PD_CPU0_BIST_ENABLE";
16"PD_CPU0_TXT_PLTEN";
17"PD_CPU1_TEST14";
18"PD_CPU1_TEST13";
19"PD_CPU0_KSFC_DIS";
20"PD_CPU1_TEST12";
21"PD_CPU1_BIST_ENABLE";
22"H_CPU1_BMCINIT";
23"PU_CPU1_FRMAGENT";
24"PD_CPU1_DMIMODE_OVERRIDE";
25"PD_CPU1_KSFC_DIS";
26"H_CPU0_BMCINIT";
27"PU_CPU0_TXT_AGENT";
28"PU_CPU1_LEGACY_SKT";
29"PD_CPU1_EAR_N";
30"PU_CPU0_FRMAGENT";
31"PU_CPU0_SAFE_MODE_BOOT";
32"PD_CPU0_EAR_N";
33"PU_CPU0_LEGACY_SKT";
34"PD_CPU0_TEST14";
35"PD_CPU0_TEST13";
36"PD_CPU0_TEST12";
37"PU_CPU1_SAFE_MODE_BOOT";
38"PU_CPU0_SOCKET_ID_1";
39"PU_CPU0_SOCKET_ID_0";
40"PU_CPU1_TXT_AGENT";
%"RES"
"1","(-425,850)","0","mstr_discrete","I100";
;
CDS_SEC"1"
PART_NUMBER"G21796-294"
WATTAGE"1/16W"
TOLERANCE"1.0%"
VALUE"240"
MATERIAL"CHIP"
PACK_TYPE"0402"
LOCATION"R7P14"
SEC"1"
SEC_TYPE"0402"
CDS_LIB"mstr_discrete"
BOM_COST"PROC"
ROOM"PROC_SIDEBAND"
CDS_LOCATION"R7P14";
"B"
$PN"2"24;
"A"
$PN"1"1;
%"RES"
"1","(-575,3400)","0","mstr_discrete","I101";
;
CDS_SEC"1"
MATERIAL"EMPTY"
PACK_TYPE"0402"
TOLERANCE"1.0%"
VALUE"240"
LOCATION"R6D6"
WATTAGE"1/16W"
PART_NUMBER"G21796-294"
ROOM"PROC_SIDEBAND"
SEC"1"
SEC_TYPE"0402"
CDS_LIB"mstr_discrete"
BOM_COST"PROC"
CDS_LOCATION"R6D6";
"B"
$PN"2"16;
"A"
$PN"1"3;
%"RES"
"1","(-425,1275)","0","mstr_discrete","I102";
;
CDS_SEC"1"
VALUE"240"
TOLERANCE"1.0%"
MATERIAL"EMPTY"
PACK_TYPE"0402"
PART_NUMBER"G21796-294"
LOCATION"R3D12"
WATTAGE"1/16W"
ROOM"PROC_SIDEBAND"
SEC_TYPE"0402"
SEC"1"
BOM_COST"PROC"
CDS_LIB"mstr_discrete"
CDS_LOCATION"R3D12";
"B"
$PN"2"12;
"A"
$PN"1"1;
%"RES"
"1","(-2450,1875)","0","mstr_discrete","I17";
;
CDS_SEC"1"
LOCATION"R3D22"
VALUE"240"
PACK_TYPE"0402"
MATERIAL"EMPTY"
PART_NUMBER"G21796-294"
WATTAGE"1/16W"
TOLERANCE"1.0%"
SEC_TYPE"0402"
SEC"1"
ROOM"PROC_SIDEBAND"
CDS_LIB"mstr_discrete"
BOM_COST"PROC"
CDS_LOCATION"R3D22";
"B"
$PN"2"23;
"A"
$PN"1"5;
%"GND"
"1","(-725,525)","0","mstr_symbols","I18";
;
HDL_POWER"GND"
CDS_LIB"mstr_symbols"
VOLTAGE"0"
BODY_TYPE"PLUMBING"
SIZE"1B";
"A\NAC"1;
%"RES"
"1","(-2450,1675)","0","mstr_discrete","I24";
;
CDS_SEC"1"
WATTAGE"1/16W"
TOLERANCE"1.0%"
VALUE"240"
PACK_TYPE"0402"
LOCATION"R3D16"
MATERIAL"EMPTY"
PART_NUMBER"G21796-294"
ROOM"PROC_SIDEBAND"
SEC_TYPE"0402"
SEC"1"
CDS_LIB"mstr_discrete"
BOM_COST"PROC"
CDS_LOCATION"R3D16";
"B"
$PN"2"22;
"A"
$PN"1"5;
%"RES"
"1","(-2450,1475)","0","mstr_discrete","I25";
;
PACK_TYPE"0402"
TOLERANCE"1.0%"
WATTAGE"1/16W"
LOCATION"R3D23"
VALUE"240"
MATERIAL"EMPTY"
PART_NUMBER"G21796-294"
ROOM"PROC_SIDEBAND"
$SEC"1"
CDS_SEC"1"
CDS_LIB"mstr_discrete"
BOM_COST"PROC"
CDS_LOCATION"R3D23";
"B"
$PN"2"40;
"A"
$PN"1"5;
%"RES"
"1","(-2450,1275)","0","mstr_discrete","I28";
;
CDS_SEC"1"
WATTAGE"1/16W"
PACK_TYPE"0402"
PART_NUMBER"G21796-294"
VALUE"240"
LOCATION"R3D26"
MATERIAL"EMPTY"
TOLERANCE"1.0%"
ROOM"PROC_SIDEBAND"
SEC"1"
SEC_TYPE"0402"
CDS_LIB"mstr_discrete"
BOM_COST"PROC"
CDS_LOCATION"R3D26";
"B"
$PN"2"37;
"A"
$PN"1"5;
%"RES"
"1","(-2475,4400)","0","mstr_discrete","I29";
;
CDS_SEC"1"
MATERIAL"CHIP"
PACK_TYPE"0402"
WATTAGE"1/16W"
LOCATION"R5D3"
TOLERANCE"1.0%"
PART_NUMBER"G21796-294"
VALUE"240"
SEC"1"
SEC_TYPE"0402"
ROOM"PROC_SIDEBAND"
CDS_LIB"mstr_discrete"
BOM_COST"PROC"
CDS_LOCATION"R5D3";
"B"
$PN"2"30;
"A"
$PN"1"2;
%"PVCCIO_CPU0"
"1","(-2975,4550)","0","mstr_symbols","I30";
;
HDL_POWER"PVCCIO_CPU0"
CDS_LIB"mstr_symbols"
BODY_TYPE"PLUMBING"
VOLTAGE"1.1V";
"G\NAC"2;
%"RES"
"1","(-2475,4200)","0","mstr_discrete","I31";
;
CDS_SEC"1"
LOCATION"R6D7"
VALUE"240"
TOLERANCE"1.0%"
WATTAGE"1/16W"
MATERIAL"EMPTY"
PACK_TYPE"0402"
PART_NUMBER"G21796-294"
ROOM"PROC_SIDEBAND"
SEC_TYPE"0402"
SEC"1"
BOM_COST"PROC"
CDS_LIB"mstr_discrete"
CDS_LOCATION"R6D7";
"B"
$PN"2"26;
"A"
$PN"1"2;
%"RES"
"1","(-2475,3800)","0","mstr_discrete","I33";
;
CDS_SEC"1"
WATTAGE"1/16W"
MATERIAL"EMPTY"
TOLERANCE"1.0%"
VALUE"240"
LOCATION"R6D13"
PACK_TYPE"0402"
PART_NUMBER"G21796-294"
ROOM"PROC_SIDEBAND"
SEC_TYPE"0402"
SEC"1"
CDS_LIB"mstr_discrete"
BOM_COST"PROC"
CDS_LOCATION"R6D13";
"B"
$PN"2"31;
"A"
$PN"1"2;
%"RES"
"1","(-475,4400)","0","mstr_discrete","I48";
;
CDS_SEC"1"
MATERIAL"EMPTY"
PART_NUMBER"G21796-294"
LOCATION"R6D15"
TOLERANCE"1.0%"
PACK_TYPE"0402"
VALUE"240"
WATTAGE"1/16W"
ROOM"PROC_SIDEBAND"
SEC"1"
SEC_TYPE"0402"
CDS_LIB"mstr_discrete"
BOM_COST"PROC"
CDS_LOCATION"R6D15";
"B"
$PN"2"39;
"A"
$PN"1"4;
%"RES"
"1","(-475,4200)","0","mstr_discrete","I49";
;
CDS_SEC"1"
MATERIAL"EMPTY"
PART_NUMBER"G21796-294"
TOLERANCE"1.0%"
LOCATION"R6D10"
WATTAGE"1/16W"
PACK_TYPE"0402"
VALUE"240"
CDS_LOCATION"R6D10"
BOM_COST"PROC"
CDS_LIB"mstr_discrete"
SEC_TYPE"0402"
SEC"1"
ROOM"PROC_SIDEBAND";
"B"
$PN"2"38;
"A"
$PN"1"4;
%"GND"
"1","(-900,2600)","0","mstr_symbols","I5";
;
HDL_POWER"GND"
CDS_LIB"mstr_symbols"
VOLTAGE"0"
BODY_TYPE"PLUMBING"
SIZE"1B";
"A\NAC"3;
%"PVCCIO_CPU0"
"1","(-825,4625)","0","mstr_symbols","I51";
;
CDS_LIB"mstr_symbols"
HDL_POWER"PVCCIO_CPU0"
BODY_TYPE"PLUMBING"
VOLTAGE"1.1V";
"G\NAC"4;
%"RES"
"1","(-2475,3600)","0","mstr_discrete","I52";
;
CDS_SEC"1"
VALUE"240"
TOLERANCE"1.0%"
LOCATION"R6D14"
MATERIAL"EMPTY"
PACK_TYPE"0402"
PART_NUMBER"G21796-294"
WATTAGE"1/16W"
ROOM"PROC_SIDEBAND"
SEC_TYPE"0402"
SEC"1"
BOM_COST"PROC"
CDS_LIB"mstr_discrete"
CDS_LOCATION"R6D14";
"B"
$PN"2"32;
"A"
$PN"1"9;
%"RES"
"1","(-2475,3400)","0","mstr_discrete","I53";
;
CDS_SEC"1"
PACK_TYPE"0402"
MATERIAL"CHIP"
WATTAGE"1/16W"
PART_NUMBER"G21796-294"
TOLERANCE"1.0%"
VALUE"240"
LOCATION"R4P14"
CDS_LOCATION"R4P14"
CDS_LIB"mstr_discrete"
BOM_COST"PROC"
ROOM"PROC_SIDEBAND"
SEC_TYPE"0402"
SEC"1";
"B"
$PN"2"33;
"A"
$PN"1"2;
%"RES"
"1","(-425,1675)","0","mstr_discrete","I59";
;
CDS_SEC"1"
PACK_TYPE"0402"
WATTAGE"1/16W"
LOCATION"R3D24"
VALUE"240"
TOLERANCE"1.0%"
PART_NUMBER"G21796-294"
MATERIAL"CHIP"
SEC_TYPE"0402"
SEC"1"
CDS_LOCATION"R3D24"
CDS_LIB"mstr_discrete"
BOM_COST"PROC"
ROOM"PROC_SIDEBAND";
"B"
$PN"2"13;
"A"
$PN"1"6;
%"RES"
"1","(-425,1475)","0","mstr_discrete","I60";
;
CDS_SEC"1"
WATTAGE"1/16W"
MATERIAL"EMPTY"
TOLERANCE"1.0%"
LOCATION"R3D17"
VALUE"240"
PACK_TYPE"0402"
PART_NUMBER"G21796-294"
SEC_TYPE"0402"
SEC"1"
ROOM"PROC_SIDEBAND"
BOM_COST"PROC"
CDS_LIB"mstr_discrete"
CDS_LOCATION"R3D17";
"B"
$PN"2"14;
"A"
$PN"1"6;
%"PVCCIO_CPU1"
"1","(-2950,2050)","0","mstr_symbols","I62";
;
HDL_POWER"PVCCIO_CPU1"
CDS_LIB"mstr_symbols"
BODY_TYPE"PLUMBING"
VOLTAGE"1.1V";
"G\NAC"5;
%"PVCCIO_CPU1"
"1","(-725,1825)","0","mstr_symbols","I63";
;
CDS_LIB"mstr_symbols"
HDL_POWER"PVCCIO_CPU1"
BODY_TYPE"PLUMBING"
VOLTAGE"1.1V";
"G\NAC"6;
%"RES"
"1","(-2450,1025)","0","mstr_discrete","I66";
;
CDS_SEC"1"
PACK_TYPE"0402"
MATERIAL"EMPTY"
WATTAGE"1/16W"
TOLERANCE"1.0%"
VALUE"240"
LOCATION"R3D25"
PART_NUMBER"G21796-294"
ROOM"PROC_SIDEBAND"
SEC_TYPE"0402"
SEC"1"
BOM_COST"PROC"
CDS_LIB"mstr_discrete"
CDS_LOCATION"R3D25";
"B"
$PN"2"29;
"A"
$PN"1"10;
%"RES"
"1","(-575,3000)","0","mstr_discrete","I68";
;
CDS_SEC"1"
VALUE"240"
LOCATION"R4P6"
PART_NUMBER"G21796-294"
TOLERANCE"1.0%"
WATTAGE"1/16W"
PACK_TYPE"0402"
MATERIAL"EMPTY"
CDS_LOCATION"R4P6"
BOM_COST"PROC"
CDS_LIB"mstr_discrete"
SEC_TYPE"0402"
SEC"1"
ROOM"PROC_SIDEBAND";
"B"
$PN"2"11;
"A"
$PN"1"3;
%"RES"
"1","(-575,2800)","0","mstr_discrete","I72";
;
CDS_SEC"1"
TOLERANCE"1.0%"
WATTAGE"1/16W"
MATERIAL"EMPTY"
PART_NUMBER"G21796-294"
LOCATION"R4P7"
VALUE"240"
PACK_TYPE"0402"
CDS_LOCATION"R4P7"
CDS_LIB"mstr_discrete"
BOM_COST"PROC"
SEC"1"
SEC_TYPE"0402"
ROOM"PROC_SIDEBAND";
"B"
$PN"2"19;
"A"
$PN"1"3;
%"RES"
"1","(-425,650)","0","mstr_discrete","I74";
;
CDS_SEC"1"
LOCATION"R7P15"
TOLERANCE"1.0%"
VALUE"240"
WATTAGE"1/16W"
PACK_TYPE"0402"
PART_NUMBER"G21796-294"
MATERIAL"EMPTY"
ROOM"PROC_SIDEBAND"
SEC_TYPE"0402"
SEC"1"
BOM_COST"PROC"
CDS_LIB"mstr_discrete"
CDS_LOCATION"R7P15";
"B"
$PN"2"25;
"A"
$PN"1"1;
%"RES"
"1","(-2450,800)","0","mstr_discrete","I76";
;
CDS_SEC"1"
PACK_TYPE"0402"
MATERIAL"EMPTY"
WATTAGE"1/16W"
LOCATION"R7P22"
VALUE"240"
TOLERANCE"1.0%"
PART_NUMBER"G21796-294"
SEC"1"
SEC_TYPE"0402"
ROOM"PROC_SIDEBAND"
BOM_COST"PROC"
CDS_LIB"mstr_discrete"
CDS_LOCATION"R7P22";
"B"
$PN"2"28;
"A"
$PN"1"5;
%"GND"
"1","(-1225,2725)","0","mstr_symbols","I78";
;
SIZE"1B"
CDS_LIB"mstr_symbols"
VOLTAGE"0.0V"
BODY_TYPE"PLUMBING"
HDL_POWER"GND";
"A\NAC"7;
%"RES"
"1","(-1575,3200)","0","mstr_discrete","I79";
;
CDS_SEC"1"
PART_NUMBER"G21796-047"
TOLERANCE"1%"
PACK_TYPE"0402"
MATERIAL"CHIP"
LOCATION"R5P2"
VALUE"49.9"
WATTAGE"1/16W"
ROOM"CPU0"
SEC"1"
SEC_TYPE"0402"
CDS_LOCATION"R5P2"
CDS_LIB"mstr_discrete";
"B"
$PN"2"7;
"A"
$PN"1"34;
%"RES"
"1","(-1575,3075)","0","mstr_discrete","I80";
;
CDS_SEC"1"
LOCATION"R5P3"
PACK_TYPE"0402"
MATERIAL"CHIP"
TOLERANCE"1%"
VALUE"49.9"
PART_NUMBER"G21796-047"
WATTAGE"1/16W"
ROOM"CPU0"
SEC_TYPE"0402"
SEC"1"
CDS_LOCATION"R5P3"
CDS_LIB"mstr_discrete";
"B"
$PN"2"7;
"A"
$PN"1"35;
%"RES"
"1","(-1575,2925)","0","mstr_discrete","I81";
;
CDS_SEC"1"
TOLERANCE"1%"
VALUE"49.9"
PACK_TYPE"0402"
MATERIAL"CHIP"
LOCATION"R6D5"
PART_NUMBER"G21796-047"
WATTAGE"1/16W"
SEC_TYPE"0402"
SEC"1"
ROOM"CPU0"
CDS_LOCATION"R6D5"
CDS_LIB"mstr_discrete";
"B"
$PN"2"7;
"A"
$PN"1"36;
%"RES"
"1","(325,2475)","0","mstr_discrete","I85";
;
CDS_SEC"1"
MATERIAL"CHIP"
PACK_TYPE"0402"
VALUE"49.9"
TOLERANCE"1%"
PART_NUMBER"G21796-047"
LOCATION"R8P1"
WATTAGE"1/16W"
ROOM"CPU1"
SEC"1"
SEC_TYPE"0402"
CDS_LOCATION"R8P1"
CDS_LIB"mstr_discrete";
"B"
$PN"2"8;
"A"
$PN"1"17;
%"RES"
"1","(325,2350)","0","mstr_discrete","I86";
;
CDS_SEC"1"
TOLERANCE"1%"
PACK_TYPE"0402"
PART_NUMBER"G21796-047"
MATERIAL"CHIP"
LOCATION"R8P2"
VALUE"49.9"
WATTAGE"1/16W"
SEC"1"
SEC_TYPE"0402"
ROOM"CPU1"
CDS_LOCATION"R8P2"
CDS_LIB"mstr_discrete";
"B"
$PN"2"8;
"A"
$PN"1"18;
%"GND"
"1","(675,2000)","0","mstr_symbols","I87";
;
HDL_POWER"GND"
BODY_TYPE"PLUMBING"
SIZE"1B"
CDS_LIB"mstr_symbols"
VOLTAGE"0.0V";
"A\NAC"8;
%"RES"
"1","(325,2200)","0","mstr_discrete","I88";
;
CDS_SEC"1"
MATERIAL"CHIP"
PACK_TYPE"0402"
LOCATION"R3D9"
TOLERANCE"1%"
PART_NUMBER"G21796-047"
VALUE"49.9"
WATTAGE"1/16W"
SEC_TYPE"0402"
ROOM"CPU1"
SEC"1"
CDS_LOCATION"R3D9"
CDS_LIB"mstr_discrete";
"B"
$PN"2"8;
"A"
$PN"1"20;
%"GND"
"1","(-2900,3500)","0","mstr_symbols","I92";
;
SIZE"1B"
CDS_LIB"mstr_symbols"
VOLTAGE"0.0V"
BODY_TYPE"PLUMBING"
HDL_POWER"GND";
"A\NAC"9;
%"GND"
"1","(-2850,900)","0","mstr_symbols","I93";
;
HDL_POWER"GND"
BODY_TYPE"PLUMBING"
VOLTAGE"0.0V"
CDS_LIB"mstr_symbols"
SIZE"1B";
"A\NAC"10;
%"RES"
"1","(-2475,4000)","0","mstr_discrete","I96";
;
CDS_SEC"1"
LOCATION"R5D4"
PACK_TYPE"0402"
TOLERANCE"1.0%"
VALUE"240"
WATTAGE"1/16W"
MATERIAL"CHIP"
PART_NUMBER"G21796-294"
SEC"1"
SEC_TYPE"0402"
ROOM"PROC_SIDEBAND"
CDS_LIB"mstr_discrete"
BOM_COST"PROC"
CDS_LOCATION"R5D4";
"B"
$PN"2"27;
"A"
$PN"1"2;
%"RES"
"1","(-575,3200)","0","mstr_discrete","I98";
;
CDS_SEC"1"
WATTAGE"1/16W"
MATERIAL"EMPTY"
TOLERANCE"1.0%"
VALUE"240"
PART_NUMBER"G21796-294"
PACK_TYPE"0402"
LOCATION"R4P1"
CDS_LOCATION"R4P1"
ROOM"PROC_SIDEBAND"
SEC"1"
SEC_TYPE"0402"
CDS_LIB"mstr_discrete"
BOM_COST"PROC";
"B"
$PN"2"15;
"A"
$PN"1"3;
%"RES"
"1","(-425,1050)","0","mstr_discrete","I99";
;
CDS_SEC"1"
WATTAGE"1/16W"
LOCATION"R3D13"
VALUE"240"
TOLERANCE"1.0%"
MATERIAL"EMPTY"
PACK_TYPE"0402"
PART_NUMBER"G21796-294"
CDS_LOCATION"R3D13"
ROOM"PROC_SIDEBAND"
SEC_TYPE"0402"
SEC"1"
BOM_COST"PROC"
CDS_LIB"mstr_discrete";
"B"
$PN"2"21;
"A"
$PN"1"1;
END.
